# T6G (Grand Teton) — schematic parts with pin connectivity, parts 8227–8227 of 8303; source: Cadence DE-HDL packaged netlist (pstxprt.dat, pstxnet.dat, pstchip.dat)

U6010  PT5161LRS  IC  pkg BGA354_8-9X22-8  page 274
  A1  NCF_GND1  POWER  = NCF_A1_CPU0_P0_GND
  A35  NCF_GND2  POWER  = NCF_CPU0_P0_GND
  AA10  B_PETN1  OUT  = P5E_CPU0_P0_TX_BUF_DN<14>
  AA29  A_PETN1  OUT  = P5E_CPU0_P0_RX_DN<14>
  AB1  A_PERP1  IN  = P5E_CPU0_P0_RX_BUF_DP<14>
  AB35  B_PERN1  IN  = P5E_CPU0_P0_TX_C_DP<14>
  AC4  GND4  POWER  = GND
  AC13  GND1  POWER  = GND
  AC17  PWR_2A_1  POWER  = P0V9_CPU0_RT0_2A
  AC20  PWR_2A_2  POWER  = P0V9_CPU0_RT0_2A
  AC22  GND2  POWER  = GND
  AC32  GND3  POWER  = GND
  AD2  GND5  POWER  = GND
  AD34  GND6  POWER  = GND
  AE1  GND7  POWER  = GND
  AE35  GND8  POWER  = GND
  AF7  B_PETP2  OUT  = P5E_CPU0_P0_TX_BUF_DP<13>
  AF26  A_PETP2  OUT  = P5E_CPU0_P0_RX_DP<13>
  AG2  A_PERN2  IN  = P5E_CPU0_P0_RX_BUF_DN<13>
  AG34  B_PERP2  IN  = P5E_CPU0_P0_TX_C_DP<13>
  AH10  B_PETN2  OUT  = P5E_CPU0_P0_TX_BUF_DN<13>
  AH29  A_PETN2  OUT  = P5E_CPU0_P0_RX_DN<13>
  AJ1  A_PERP2  IN  = P5E_CPU0_P0_RX_BUF_DP<13>
  AJ35  B_PERN2  IN  = P5E_CPU0_P0_TX_C_DN<13>
  AK4  GND12  POWER  = GND
  AK13  GND9  POWER  = GND
  AK17  PWR_2A_3  POWER  = P0V9_CPU0_RT0_2A
  AK20  PWR_2A_4  POWER  = P0V9_CPU0_RT0_2A
  AK22  GND10  POWER  = GND
  AK32  GND11  POWER  = GND
  AL2  GND13  POWER  = GND
  AL34  GND14  POWER  = GND
  AM1  GND15  POWER  = GND
  AM35  GND16  POWER  = GND
  AN7  B_PETP3  OUT  = P5E_CPU0_P0_TX_BUF_DP<12>
  AN26  A_PETP3  OUT  = P5E_CPU0_P0_RX_DP<12>
  AP2  A_PERN3  IN  = P5E_CPU0_P0_RX_BUF_DN<12>
  AP34  B_PERP3  IN  = P5E_CPU0_P0_TX_C_DN<12>
  AR10  B_PETN3  OUT  = P5E_CPU0_P0_TX_BUF_DN<12>
  AR29  A_PETN3  OUT  = P5E_CPU0_P0_RX_DN<12>
  AT1  A_PERP3  IN  = P5E_CPU0_P0_RX_BUF_DP<12>
  AT35  B_PERN3  IN  = P5E_CPU0_P0_TX_C_DP<12>
  AU4  GND20  POWER  = GND
  AU13  GND17  POWER  = GND
  AU17  PWR_2A_5  POWER  = P0V9_CPU0_RT0_2A
  AU20  PWR_2A_6  POWER  = P0V9_CPU0_RT0_2A
  AU22  GND18  POWER  = GND
  AU32  GND19  POWER  = GND
  AV2  GND21  POWER  = GND
  AV34  GND22  POWER  = GND
  AW1  GND23  POWER  = GND
  AW35  GND24  POWER  = GND
  AY7  B_PETP4  OUT  = P5E_CPU0_P0_TX_BUF_DP<11>
  AY26  A_PETP4  OUT  = P5E_CPU0_P0_RX_DP<11>
  B3  JTAG_TCK  IN  = JTAG_TCK_RT_CPU0_P0
  B6  JTAG_TDI  IN  = JTAG_TDI_RT_CPU0_P0
  B9  JTAG_TDO  OUT  = JTAG_TDO_RT_CPU0_P0
  B12  JTAG_TMS  IN  = JTAG_TMS_RT_CPU0_P0
  B16  REFCLK_OUTP  OUT  = NC
  B19  GND25  POWER  = GND
  B23  SMB_ADDR2  IN  = RT_CPU0_P0_ADDR2
  B25  SMB_ADDR3  IN  = RT_CPU0_P0_ADDR3
  B28  SMBDAT  BI  = SMB_RT_CPU0_P0_R2_SDA
  B31  SMBCLK  BI  = SMB_RT_CPU0_P0_R2_SCL
  BA2  A_PERN4  IN  = P5E_CPU0_P0_RX_BUF_DN<11>
  BA34  B_PERP4  IN  = P5E_CPU0_P0_TX_C_DN<11>
  BB10  B_PETN4  OUT  = P5E_CPU0_P0_TX_BUF_DN<11>
  BB29  A_PETN4  OUT  = P5E_CPU0_P0_RX_DN<11>
  BC1  A_PERP4  IN  = P5E_CPU0_P0_RX_BUF_DP<11>
  BC35  B_PERN4  IN  = P5E_CPU0_P0_TX_C_DP<11>
  BD4  GND29  POWER  = GND
  BD13  GND26  POWER  = GND
  BD17  PWR_2A_7  POWER  = P0V9_CPU0_RT0_2A_2D
  BD20  PWR_2A_8  POWER  = P0V9_CPU0_RT0_2A_2D
  BD22  GND27  POWER  = GND
  BD32  GND28  POWER  = GND
  BE2  GND30  POWER  = GND
  BE34  GND31  POWER  = GND
  BF1  GND32  POWER  = GND
  BF35  GND33  POWER  = GND
  BG7  B_PETP5  OUT  = P5E_CPU0_P0_TX_BUF_DP<10>
  BG26  A_PETP5  OUT  = P5E_CPU0_P0_RX_DP<10>
  BH2  A_PERN5  IN  = P5E_CPU0_P0_RX_BUF_DN<10>
  BH34  B_PERP5  IN  = P5E_CPU0_P0_TX_C_DN<10>
  BJ10  B_PETN5  OUT  = P5E_CPU0_P0_TX_BUF_DN<10>
  BJ29  A_PETN5  OUT  = P5E_CPU0_P0_RX_DN<10>
  BK1  A_PERP5  IN  = P5E_CPU0_P0_RX_BUF_DP<10>
  BK35  B_PERN5  IN  = P5E_CPU0_P0_TX_C_DP<10>
  BL4  GND37  POWER  = GND
  BL13  GND34  POWER  = GND
  BL17  PWR_2D_1  POWER  = P0V9_CPU0_RT_2D
  BL20  PWR_2D_2  POWER  = P0V9_CPU0_RT_2D
  BL22  GND35  POWER  = GND
  BL32  GND36  POWER  = GND
  BM2  GND38  POWER  = GND
  BM34  GND39  POWER  = GND
  BN1  GND40  POWER  = GND
  BN35  GND41  POWER  = GND
  BP7  B_PETP6  OUT  = P5E_CPU0_P0_TX_BUF_DP<9>
  BP26  A_PETP6  OUT  = P5E_CPU0_P0_RX_DP<9>
  BR2  A_PERN6  IN  = P5E_CPU0_P0_RX_BUF_DN<9>
  BR34  B_PERP6  IN  = P5E_CPU0_P0_TX_C_DN<9>
  BT10  B_PETN6  OUT  = P5E_CPU0_P0_TX_BUF_DN<9>
  BT29  A_PETN6  OUT  = P5E_CPU0_P0_RX_DN<9>
  BU1  A_PERP6  IN  = P5E_CPU0_P0_RX_BUF_DP<9>
  BU35  B_PERN6  IN  = P5E_CPU0_P0_TX_C_DP<9>
  BV4  GND45  POWER  = GND
  BV13  GND42  POWER  = GND
  BV17  PWR_1D  POWER  = P1V8_CPU0_RT0_1A_1D
  BV20  PWR_1A_1  POWER  = P1V8_CPU0_RT0_1A
  BV22  GND43  POWER  = GND
  BV32  GND44  POWER  = GND
  BW2  GND46  POWER  = GND
  BW34  GND47  POWER  = GND
  BY1  GND48  POWER  = GND
  BY35  GND49  POWER  = GND
  C2  NCF_GND3  POWER  = NCF_CPU0_P0_GND
  C34  NCF_GND4  POWER  = NCF_CPU0_P0_GND
  CA7  B_PETP7  OUT  = P5E_CPU0_P0_TX_BUF_DP<8>
  CA26  A_PETP7  OUT  = P5E_CPU0_P0_RX_DP<8>
  CB2  A_PERN7  IN  = P5E_CPU0_P0_RX_BUF_DN<8>
  CB34  B_PERP7  IN  = P5E_CPU0_P0_TX_C_DN<8>
  CC10  B_PETN7  OUT  = P5E_CPU0_P0_TX_BUF_DN<8>
  CC29  A_PETN7  OUT  = P5E_CPU0_P0_RX_DN<8>
  CD1  A_PERP7  IN  = P5E_CPU0_P0_RX_BUF_DP<8>
  CD35  B_PERN7  IN  = P5E_CPU0_P0_TX_C_DP<8>
  CE4  GND53  POWER  = GND
  CE13  GND50  POWER  = GND
  CE17  PWR_1A_2  POWER  = P1V8_CPU0_RT0_1A
  CE20  PWR_1A_3  POWER  = P1V8_CPU0_RT0_1A
  CE22  GND51  POWER  = GND
  CE32  GND52  POWER  = GND
  CF2  GND54  POWER  = GND
  CF34  GND55  POWER  = GND
  CG1  GND56  POWER  = GND
  CG35  GND57  POWER  = GND
  CH7  B_PETP8  OUT  = P5E_CPU0_P0_TX_BUF_DP<7>
  CH26  A_PETP8  OUT  = P5E_CPU0_P0_RX_DP<7>
  CJ2  A_PERN8  IN  = P5E_CPU0_P0_RX_BUF_DN<7>
  CJ34  B_PERP8  IN  = P5E_CPU0_P0_TX_C_DN<7>
  CK10  B_PETN8  OUT  = P5E_CPU0_P0_TX_BUF_DN<7>
  CK29  A_PETN8  OUT  = P5E_CPU0_P0_RX_DN<7>
  CL1  A_PERP8  IN  = P5E_CPU0_P0_RX_BUF_DP<7>
  CL35  B_PERN8  IN  = P5E_CPU0_P0_TX_C_DP<7>
  CM4  GND61  POWER  = GND
  CM13  GND58  POWER  = GND
  CM17  PWR_1A_4  POWER  = P1V8_CPU0_RT0_1A
  CM20  PWR_1A_5  POWER  = P1V8_CPU0_RT0_1A
  CM22  GND59  POWER  = GND
  CM32  GND60  POWER  = GND
  CN2  GND62  POWER  = GND
  CN34  GND63  POWER  = GND
  CP1  GND64  POWER  = GND
  CP35  GND65  POWER  = GND
  CR7  B_PETP9  OUT  = P5E_CPU0_P0_TX_BUF_DP<6>
  CR26  A_PETP9  OUT  = P5E_CPU0_P0_RX_DP<6>
  CT2  A_PERN9  IN  = P5E_CPU0_P0_RX_BUF_DN<6>
  CT34  B_PERP9  IN  = P5E_CPU0_P0_TX_C_DN<6>
  CU10  B_PETN9  OUT  = P5E_CPU0_P0_TX_BUF_DN<6>
  CU29  A_PETN9  OUT  = P5E_CPU0_P0_RX_DN<6>
  CV1  A_PERP9  IN  = P5E_CPU0_P0_RX_BUF_DP<6>
  CV35  B_PERN9  IN  = P5E_CPU0_P0_TX_C_DP<6>
  CW4  GND69  POWER  = GND
  CW13  GND66  POWER  = GND
  CW17  PWR_2D_3  POWER  = P0V9_CPU0_RT_2D
  CW20  PWR_2D_4  POWER  = P0V9_CPU0_RT_2D
  CW22  GND67  POWER  = GND
  CW32  GND68  POWER  = GND
  CY2  GND70  POWER  = GND
  CY34  GND71  POWER  = GND
  D1  NCF_GND5  POWER  = NCF_CPU0_P0_GND
  D35  NCF_GND6  POWER  = NCF_CPU0_P0_GND
  DA1  GND72  POWER  = GND
  DA35  GND73  POWER  = GND
  DB7  B_PETP10  OUT  = P5E_CPU0_P0_TX_BUF_DP<5>
  DB26  A_PETP10  OUT  = P5E_CPU0_P0_RX_DP<5>
  DC2  A_PERN10  IN  = P5E_CPU0_P0_RX_BUF_DN<5>
  DC34  B_PERP10  IN  = P5E_CPU0_P0_TX_C_DN<5>
  DD10  B_PETN10  OUT  = P5E_CPU0_P0_TX_BUF_DN<5>
  DD29  A_PETN10  OUT  = P5E_CPU0_P0_RX_DN<5>
  DE1  A_PERP10  IN  = P5E_CPU0_P0_RX_BUF_DP<5>
  DE35  B_PERN10  IN  = P5E_CPU0_P0_TX_C_DP<5>
  DF4  GND77  POWER  = GND
  DF13  GND74  POWER  = GND
  DF17  PWR_2A_9  POWER  = P0V9_CPU0_RT0_2A_2D
  DF20  PWR_2A_10  POWER  = P0V9_CPU0_RT0_2A_2D
  DF22  GND75  POWER  = GND
  DF32  GND76  POWER  = GND
  DG2  GND78  POWER  = GND
  DG34  GND79  POWER  = GND
  DH1  GND80  POWER  = GND
  DH35  GND81  POWER  = GND
  DJ7  B_PETP11  OUT  = P5E_CPU0_P0_TX_BUF_DP<4>
  DJ26  A_PETP11  OUT  = P5E_CPU0_P0_RX_DP<4>
  DK2  A_PERN11  IN  = P5E_CPU0_P0_RX_BUF_DN<4>
  DK34  B_PERP11  IN  = P5E_CPU0_P0_TX_C_DN<4>
  DL10  B_PETN11  OUT  = P5E_CPU0_P0_TX_BUF_DN<4>
  DL29  A_PETN11  OUT  = P5E_CPU0_P0_RX_DN<4>
  DM1  A_PERP11  IN  = P5E_CPU0_P0_RX_BUF_DP<4>
  DM35  B_PERN11  IN  = P5E_CPU0_P0_TX_C_DP<4>
  DN4  GND85  POWER  = GND
  DN13  GND82  POWER  = GND
  DN17  PWR_2A_11  POWER  = P0V9_CPU0_RT0_2A
  DN20  PWR_2A_12  POWER  = P0V9_CPU0_RT0_2A
  DN22  GND83  POWER  = GND
  DN32  GND84  POWER  = GND
  DP2  GND86  POWER  = GND
  DP34  GND87  POWER  = GND
  DR1  GND88  POWER  = GND
  DR35  GND89  POWER  = GND
  DT7  B_PETP12  OUT  = P5E_CPU0_P0_TX_BUF_DP<3>
  DT26  A_PETP12  OUT  = P5E_CPU0_P0_RX_DP<3>
  DU2  A_PERN12  IN  = P5E_CPU0_P0_RX_BUF_DN<3>
  DU34  B_PERP12  IN  = P5E_CPU0_P0_TX_C_DN<3>
  DV10  B_PETN12  OUT  = P5E_CPU0_P0_TX_BUF_DN<3>
  DV29  A_PETN12  OUT  = P5E_CPU0_P0_RX_DN<3>
  DW1  A_PERP12  IN  = P5E_CPU0_P0_RX_BUF_DP<3>
  DW35  B_PERN12  IN  = P5E_CPU0_P0_TX_C_DP<3>
  DY4  GND93  POWER  = GND
  DY13  GND90  POWER  = GND
  DY17  PWR_2A_13  POWER  = P0V9_CPU0_RT0_2A
  DY20  PWR_2A_14  POWER  = P0V9_CPU0_RT0_2A
  DY22  GND91  POWER  = GND
  DY32  GND92  POWER  = GND
  E8  JTAG_TRST_N  IN  = JTAG_TRST_RT_CPU0_P0_N
  E11  RXDET_BYP  IN  = RXDET_BYP_RT_CPU0_P0
  E14  GND94  POWER  = GND
  E18  REFCLK_OUTN  OUT  = NC
  E27  GND95  POWER  = GND
  E30  T_SENSE  OUT  = GND
  E33  GND96  POWER  = GND
  EA2  GND97  POWER  = GND
  EA34  GND98  POWER  = GND
  EB1  GND99  POWER  = GND
  EB35  GND100  POWER  = GND
  EC7  B_PETP13  OUT  = P5E_CPU0_P0_TX_BUF_DP<2>
  EC26  A_PETP13  OUT  = P5E_CPU0_P0_RX_DP<2>
  ED2  A_PERN13  IN  = P5E_CPU0_P0_RX_BUF_DN<2>
  ED34  B_PERP13  IN  = P5E_CPU0_P0_TX_C_DN<2>
  EE10  B_PETN13  OUT  = P5E_CPU0_P0_TX_BUF_DN<2>
  EE29  A_PETN13  OUT  = P5E_CPU0_P0_RX_DN<2>
  EF1  A_PERP13  IN  = P5E_CPU0_P0_RX_BUF_DP<2>
  EF35  B_PERN13  IN  = P5E_CPU0_P0_TX_C_DP<2>
  EG4  GND104  POWER  = GND
  EG13  GND101  POWER  = GND
  EG17  PWR_2A_15  POWER  = P0V9_CPU0_RT0_2A
  EG20  PWR_2A_16  POWER  = P0V9_CPU0_RT0_2A
  EG22  GND102  POWER  = GND
  EG32  GND103  POWER  = GND
  EH2  GND105  POWER  = GND
  EH34  GND106  POWER  = GND
  EJ1  GND107  POWER  = GND
  EJ35  GND108  POWER  = GND
  EK7  B_PETP14  OUT  = P5E_CPU0_P0_TX_BUF_DP<1>
  EK26  A_PETP14  OUT  = P5E_CPU0_P0_RX_DP<1>
  EL2  A_PERN14  IN  = P5E_CPU0_P0_RX_BUF_DN<1>
  EL34  B_PERP14  IN  = P5E_CPU0_P0_TX_C_DP<1>
  EM10  B_PETN14  OUT  = P5E_CPU0_P0_TX_BUF_DN<1>
  EM29  A_PETN14  OUT  = P5E_CPU0_P0_RX_DN<1>
  EN1  A_PERP14  IN  = P5E_CPU0_P0_RX_BUF_DP<1>
  EN35  B_PERN14  IN  = P5E_CPU0_P0_TX_C_DN<1>
  EP4  GND112  POWER  = GND
  EP13  GND109  POWER  = GND
  EP17  PWR_2A_17  POWER  = P0V9_CPU0_RT0_2A
  EP20  PWR_2A_18  POWER  = P0V9_CPU0_RT0_2A
  EP22  GND110  POWER  = GND
  EP32  GND111  POWER  = GND
  ER2  GND113  POWER  = GND
  ER34  GND114  POWER  = GND
  ET1  GND115  POWER  = GND
  ET35  GND116  POWER  = GND
  EU7  B_PETP15  OUT  = P5E_CPU0_P0_TX_BUF_DP<0>
  EU26  A_PETP15  OUT  = P5E_CPU0_P0_RX_DP<0>
  EV2  A_PERN15  IN  = P5E_CPU0_P0_RX_BUF_DN<0>
  EV34  B_PERP15  IN  = P5E_CPU0_P0_TX_C_DN<0>
  EW10  B_PETN15  OUT  = P5E_CPU0_P0_TX_BUF_DN<0>
  EW29  A_PETN15  OUT  = P5E_CPU0_P0_RX_DN<0>
  EY1  A_PERP15  IN  = P5E_CPU0_P0_RX_BUF_DP<0>
  EY35  B_PERN15  IN  = P5E_CPU0_P0_TX_C_DP<0>
  F2  PERST_N  IN  = RST_RT_CPU0_P0_PERST_N
  F34  SMB_ADDR1  IN  = RT_CPU0_P0_ADDR1
  FA15  GND117  POWER  = GND
  FA32  GND118  POWER  = GND
  FB2  GND119  POWER  = GND
  FB34  GND120  POWER  = GND
  FC3  GND125  POWER  = GND
  FC6  GND126  POWER  = GND
  FC9  GND127  POWER  = GND
  FC19  GND121  POWER  = GND
  FC23  GND122  POWER  = GND
  FC25  GND123  POWER  = GND
  FC28  GND124  POWER  = GND
  FD1  GND128  POWER  = GND
  FD35  GND129  POWER  = GND
  FE2  NCF_GND7  POWER  = NCF_CPU0_P0_GND
  FE34  NCF_GND8  POWER  = NCF_CPU0_P0_GND
  FF5  EE_CLK  BI  = SMB_RT_CPU0_P0_ROM_MUX_1D_R_SCL
  FF8  JTAG_TEST_MODE  IN  = JTAG_TEST_MODE_RT_CPU0_P0
  FF11  RESET_N  IN  = RST_RT_CPU0_P0_RESET_N
  FF14  GND130  POWER  = GND
  FF18  REFCLKN  IN  = CLK_100M_RETIMER_CPU0_P0_DN
  FF21  GND131  POWER  = GND
  FF24  TEST0  BI  = TEST0_RT_CPU0_P0
  FF27  TEST1  BI  = TEST1_RT_CPU0_P0
  FF30  TEST2  BI  = TEST2_RT_CPU0_P0
  FF33  SCAN_MODE  IN  = RT_CPU0_P0_SCAN_MODE
  FG1  NCF_GND9  POWER  = NCF_CPU0_P0_GND
  FG35  NCF_GND10  POWER  = NCF_CPU0_P0_GND
  FH2  NCF_GND11  POWER  = NCF_CPU0_P0_GND
  FH34  NCF_GND12  POWER  = NCF_CPU0_P0_GND
  FJ3  EE_DAT  BI  = SMB_RT_CPU0_P0_ROM_MUX_1D_R_SDA
  FJ6  GPIO0  BI  = NC
  FJ9  MODE  IN  = MODE_RT_CPU0_P0
  FJ12  GND132  POWER  = GND
  FJ16  REFCLKP  IN  = CLK_100M_RETIMER_CPU0_P0_DP
  FJ19  GND133  POWER  = GND
  FJ23  GPIO1  BI  = NC
  FJ25  GPIO2  BI  = GPIO2_RT_CPU0_P0
  FJ28  GPIO3  BI  = GPIO3_RT_CPU0_P0
  FJ31  INT_N  OUT  = NC
  G1  VQPS  IN  = RT_CPU0_P0_VQPS
  G35  CLKREQ_N  IN  = CLKREQ_RT_CPU0_P0_N
  H12  GND134  POWER  = GND
  H16  GND135  POWER  = GND
  H19  GND136  POWER  = GND
  H31  GND137  POWER  = GND
  J4  GND139  POWER  = GND
  J22  GND138  POWER  = GND
  K2  GND140  POWER  = GND
  K34  GND141  POWER  = GND
  L1  GND142  POWER  = GND
  L35  GND143  POWER  = GND
  M7  B_PETP0  OUT  = P5E_CPU0_P0_TX_BUF_DP<15>
  M26  A_PETP0  OUT  = P5E_CPU0_P0_RX_DP<15>
  N2  A_PERN0  IN  = P5E_CPU0_P0_RX_BUF_DN<15>
  N34  B_PERP0  IN  = P5E_CPU0_P0_TX_C_DN<15>
  P10  B_PETN0  OUT  = P5E_CPU0_P0_TX_BUF_DN<15>
  P29  A_PETN0  OUT  = P5E_CPU0_P0_RX_DN<15>
  R1  A_PERP0  IN  = P5E_CPU0_P0_RX_BUF_DP<15>
  R35  B_PERN0  IN  = P5E_CPU0_P0_TX_C_DP<15>
  T4  GND147  POWER  = GND
  T13  GND144  POWER  = GND
  T17  PWR_2A_19  POWER  = P0V9_CPU0_RT0_2A
  T20  PWR_2A_20  POWER  = P0V9_CPU0_RT0_2A
  T22  GND145  POWER  = GND
  T32  GND146  POWER  = GND
  U2  GND148  POWER  = GND
  U34  GND149  POWER  = GND
  V1  GND150  POWER  = GND
  V35  GND151  POWER  = GND
  W7  B_PETP1  OUT  = P5E_CPU0_P0_TX_BUF_DP<14>
  W26  A_PETP1  OUT  = P5E_CPU0_P0_RX_DP<14>
  Y2  A_PERN1  IN  = P5E_CPU0_P0_RX_BUF_DN<14>
  Y34  B_PERP1  IN  = P5E_CPU0_P0_TX_C_DN<14>
